#ISCELL
  pure_quanta quanta_title_block_c *
  *
#CELL
  pure_quanta lcmxo3lf2100c5bg256c *
  page39_i1
#ISCELL
  logical_power universal_power *
  page39_i3
